(kicad_pcb
	(version 20260206)
	(generator "pcbnew")
	(generator_version "10.0")
	(general
		(thickness 1.6)
		(legacy_teardrops no)
	)
	(paper "A4")
	(title_block
		(title "pdpb — Lightning_PDPB_BRD.brd")
		(comment 1 "Lightning (Wiwynn / Facebook NVMe JBOF) / footprints 72-78 of 1140")
	)
	(layers
		(0 "F.Cu" signal "TOP")
		(4 "In1.Cu" signal "L2GND")
		(6 "In2.Cu" signal "L3")
		(8 "In3.Cu" signal "L4VCC")
		(10 "In4.Cu" signal "L5VCC")
		(12 "In5.Cu" signal "L6")
		(14 "In6.Cu" signal "L7GND")
		(2 "B.Cu" signal "BOTTOM")
		(9 "F.Adhes" user "F.Adhesive")
		(11 "B.Adhes" user "B.Adhesive")
		(13 "F.Paste" user "Package Geometry/Pastemask Top")
		(15 "B.Paste" user "Package Geometry/Pastemask Bottom")
		(5 "F.SilkS" user "Ref Des/Silkscreen Top")
		(7 "B.SilkS" user "Ref Des/Silkscreen Bottom")
		(1 "F.Mask" user "Board Geometry/Soldermask Top")
		(3 "B.Mask" user "Board Geometry/Soldermask Bottom")
		(17 "Dwgs.User" user "User.Drawings")
		(19 "Cmts.User" user "User.Comments")
		(21 "Eco1.User" user "User.Eco1")
		(23 "Eco2.User" user "User.Eco2")
		(25 "Edge.Cuts" user "Board Geometry/Outline")
		(27 "Margin" user)
		(31 "F.CrtYd" user "Package Geometry/Place Bound Top")
		(29 "B.CrtYd" user "Package Geometry/Place Bound Bottom")
		(35 "F.Fab" user "Ref Des/Assembly Top")
		(33 "B.Fab" user "Ref Des/Assembly Bottom")
	)
	(footprint ""
		(layer "F.Cu")
		(at 233.807 -447.802 180)
		(property "Reference" "Q29"
			(at 0 0 180)
			(layer "F.SilkS")
			(hide yes)
			(effects
				(font
					(size 1.27 1.27)
				)
			)
		)
		(property "Value" "2N7002A-7-GP"
			(at 0.127 -8.9662 180)
			(unlocked yes)
			(layer "F.Fab")
			(hide yes)
			(effects
				(font
					(size 1.016 1.016)
					(thickness 0.1524)
				)
			)
		)
		(property "Device Type" "SOT23DGS2D4H48"
			(at 0.127 -10.4902 180)
			(unlocked yes)
			(layer "F.Fab")
			(hide yes)
			(effects
				(font
					(size 1.016 1.016)
					(thickness 0.1524)
				)
			)
		)
		(duplicate_pad_numbers_are_jumpers no)
		(fp_line
			(start 1.651 1.778)
			(end 1.651 -1.778)
			(stroke
				(width 0.1524)
				(type default)
			)
			(layer "F.SilkS")
		)
		(fp_line
			(start 1.651 -1.778)
			(end -1.651 -1.778)
			(stroke
				(width 0.1524)
				(type default)
			)
			(layer "F.SilkS")
		)
		(fp_line
			(start -1.651 1.778)
			(end 1.651 1.778)
			(stroke
				(width 0.1524)
				(type default)
			)
			(layer "F.SilkS")
		)
		(fp_line
			(start -1.651 -1.778)
			(end -1.651 1.778)
			(stroke
				(width 0.1524)
				(type default)
			)
			(layer "F.SilkS")
		)
		(fp_poly
			(pts
				(xy -1.778 1.8796) (xy -1.778 -1.8796) (xy 1.778 -1.8796) (xy 1.778 1.8796)
			)
			(stroke
				(width 0)
				(type default)
			)
			(fill no)
			(layer "F.CrtYd")
		)
		(fp_poly
			(pts
				(xy -1.778 1.8796) (xy -1.778 -1.8796) (xy 1.778 -1.8796) (xy 1.778 1.8796)
			)
			(stroke
				(width 0)
				(type default)
			)
			(fill no)
			(layer "F.Fab")
		)
		(pad "D" smd custom
			(at 0 -0.9525 180)
			(size 0.1905 0.1905)
			(layers "F.Cu" "F.Mask" "F.Paste")
			(net "SSD_ACT_DR0_MOS_N")
			(options
				(clearance outline)
				(anchor circle)
			)
			(primitives
				(gr_poly
					(pts
						(arc
							(start -0.1778 0.5715)
							(mid -0.321484 0.511984)
							(end -0.381 0.3683)
						)
						(arc
							(start -0.381 -0.3683)
							(mid -0.321484 -0.511984)
							(end -0.1778 -0.5715)
						)
						(arc
							(start 0.1778 -0.5715)
							(mid 0.321484 -0.511984)
							(end 0.381 -0.3683)
						)
						(arc
							(start 0.381 0.3683)
							(mid 0.321484 0.511984)
							(end 0.1778 0.5715)
						)
					)
					(width 0)
					(fill yes)
				)
			)
		)
		(pad "G" smd custom
			(at -0.98425 0.9525 180)
			(size 0.1905 0.1905)
			(layers "F.Cu" "F.Mask" "F.Paste")
			(net "ATTN_LED_DR0_AND_R")
			(options
				(clearance outline)
				(anchor circle)
			)
			(primitives
				(gr_poly
					(pts
						(arc
							(start -0.1778 0.5715)
							(mid -0.321484 0.511984)
							(end -0.381 0.3683)
						)
						(arc
							(start -0.381 -0.3683)
							(mid -0.321484 -0.511984)
							(end -0.1778 -0.5715)
						)
						(arc
							(start 0.1778 -0.5715)
							(mid 0.321484 -0.511984)
							(end 0.381 -0.3683)
						)
						(arc
							(start 0.381 0.3683)
							(mid 0.321484 0.511984)
							(end 0.1778 0.5715)
						)
					)
					(width 0)
					(fill yes)
				)
			)
		)
		(pad "S" smd custom
			(at 0.98425 0.9525 180)
			(size 0.1905 0.1905)
			(layers "F.Cu" "F.Mask" "F.Paste")
			(net "SSD_ACT_DR0_R")
			(options
				(clearance outline)
				(anchor circle)
			)
			(primitives
				(gr_poly
					(pts
						(arc
							(start -0.1778 0.5715)
							(mid -0.321484 0.511984)
							(end -0.381 0.3683)
						)
						(arc
							(start -0.381 -0.3683)
							(mid -0.321484 -0.511984)
							(end -0.1778 -0.5715)
						)
						(arc
							(start 0.1778 -0.5715)
							(mid 0.321484 -0.511984)
							(end 0.381 -0.3683)
						)
						(arc
							(start 0.381 0.3683)
							(mid 0.321484 0.511984)
							(end 0.1778 0.5715)
						)
					)
					(width 0)
					(fill yes)
				)
			)
		)
	)
	(footprint ""
		(layer "F.Cu")
		(at 92.837 -203.708)
		(property "Reference" "C8864"
			(at 0 0 0)
			(layer "F.SilkS")
			(hide yes)
			(effects
				(font
					(size 1.27 1.27)
				)
			)
		)
		(property "Value" "SCD1U16V2KX-3GP"
			(at 1.1811 -2.7051 0)
			(unlocked yes)
			(layer "F.Fab")
			(hide yes)
			(effects
				(font
					(size 1.016 1.016)
					(thickness 0.1524)
				)
			)
		)
		(property "Device Type" "C402H22"
			(at 1.1811 -4.2291 0)
			(unlocked yes)
			(layer "F.Fab")
			(hide yes)
			(effects
				(font
					(size 1.016 1.016)
					(thickness 0.1524)
				)
			)
		)
		(duplicate_pad_numbers_are_jumpers no)
		(fp_rect
			(start -0.4318 0.9525)
			(end 0.4318 -0.9525)
			(stroke
				(width 0)
				(type default)
			)
			(fill no)
			(layer "F.CrtYd")
		)
		(fp_rect
			(start -0.4318 0.9525)
			(end 0.4318 -0.9525)
			(stroke
				(width 0)
				(type default)
			)
			(fill no)
			(layer "F.Fab")
		)
		(pad "1" smd custom
			(at 0 -0.4445)
			(size 0.1524 0.1524)
			(layers "F.Cu" "F.Mask" "F.Paste")
			(net "VDD_IO_3")
			(options
				(clearance outline)
				(anchor circle)
			)
			(primitives
				(gr_poly
					(pts
						(arc
							(start 0.3048 -0.2032)
							(mid 0.275042 -0.275042)
							(end 0.2032 -0.3048)
						)
						(arc
							(start -0.2032 -0.3048)
							(mid -0.275042 -0.275042)
							(end -0.3048 -0.2032)
						)
						(arc
							(start -0.3048 0.2032)
							(mid -0.275042 0.275042)
							(end -0.2032 0.3048)
						)
						(arc
							(start 0.2032 0.3048)
							(mid 0.275042 0.275042)
							(end 0.3048 0.2032)
						)
					)
					(width 0)
					(fill yes)
				)
			)
		)
		(pad "2" smd custom
			(at 0 0.4445)
			(size 0.1524 0.1524)
			(layers "F.Cu" "F.Mask" "F.Paste")
			(net "GND")
			(options
				(clearance outline)
				(anchor circle)
			)
			(primitives
				(gr_poly
					(pts
						(arc
							(start 0.3048 -0.2032)
							(mid 0.275042 -0.275042)
							(end 0.2032 -0.3048)
						)
						(arc
							(start -0.2032 -0.3048)
							(mid -0.275042 -0.275042)
							(end -0.3048 -0.2032)
						)
						(arc
							(start -0.3048 0.2032)
							(mid -0.275042 0.275042)
							(end -0.2032 0.3048)
						)
						(arc
							(start 0.2032 0.3048)
							(mid 0.275042 0.275042)
							(end 0.3048 0.2032)
						)
					)
					(width 0)
					(fill yes)
				)
			)
		)
	)
	(footprint ""
		(layer "F.Cu")
		(at 234.061 -136.00811 90)
		(property "Reference" "R9801"
			(at 0 0 90)
			(layer "F.SilkS")
			(hide yes)
			(effects
				(font
					(size 1.27 1.27)
				)
			)
		)
		(property "Value" "0R2J-2-GP"
			(at 0.064008 -3.993896 90)
			(unlocked yes)
			(layer "F.Fab")
			(hide yes)
			(effects
				(font
					(size 1.016 1.016)
					(thickness 0.1524)
				)
			)
		)
		(property "Device Type" "R402H16"
			(at 0.064008 -5.517896 90)
			(unlocked yes)
			(layer "F.Fab")
			(hide yes)
			(effects
				(font
					(size 1.016 1.016)
					(thickness 0.1524)
				)
			)
		)
		(duplicate_pad_numbers_are_jumpers no)
		(fp_line
			(start 0.508 -0.9398)
			(end -0.508 -0.9398)
			(stroke
				(width 0.1524)
				(type default)
			)
			(layer "F.SilkS")
		)
		(fp_line
			(start -0.508 -0.9398)
			(end -0.508 0.9398)
			(stroke
				(width 0.1524)
				(type default)
			)
			(layer "F.SilkS")
		)
		(fp_rect
			(start -0.508 0.9398)
			(end 0.508 -0.9398)
			(stroke
				(width 0)
				(type default)
			)
			(fill no)
			(layer "F.CrtYd")
		)
		(fp_rect
			(start -0.508 0.9398)
			(end 0.508 -0.9398)
			(stroke
				(width 0)
				(type default)
			)
			(fill no)
			(layer "F.Fab")
		)
		(pad "1" smd custom
			(at 0 -0.4445 90)
			(size 0.1397 0.1397)
			(layers "F.Cu" "F.Mask" "F.Paste")
			(net "ATTN_LED_DR3_AND")
			(options
				(clearance outline)
				(anchor circle)
			)
			(primitives
				(gr_poly
					(pts
						(arc
							(start -0.1778 -0.2794)
							(mid -0.249642 -0.249642)
							(end -0.2794 -0.1778)
						)
						(arc
							(start -0.2794 0.1778)
							(mid -0.249642 0.249642)
							(end -0.1778 0.2794)
						)
						(arc
							(start 0.1778 0.2794)
							(mid 0.249642 0.249642)
							(end 0.2794 0.1778)
						)
						(arc
							(start 0.2794 -0.1778)
							(mid 0.249642 -0.249642)
							(end 0.1778 -0.2794)
						)
					)
					(width 0)
					(fill yes)
				)
			)
		)
		(pad "2" smd custom
			(at 0 0.4445 90)
			(size 0.1397 0.1397)
			(layers "F.Cu" "F.Mask" "F.Paste")
			(net "ATTN_LED_DR3_AND_R")
			(options
				(clearance outline)
				(anchor circle)
			)
			(primitives
				(gr_poly
					(pts
						(arc
							(start -0.1778 -0.2794)
							(mid -0.249642 -0.249642)
							(end -0.2794 -0.1778)
						)
						(arc
							(start -0.2794 0.1778)
							(mid -0.249642 0.249642)
							(end -0.1778 0.2794)
						)
						(arc
							(start 0.1778 0.2794)
							(mid 0.249642 0.249642)
							(end 0.2794 0.1778)
						)
						(arc
							(start 0.2794 -0.1778)
							(mid 0.249642 -0.249642)
							(end 0.1778 -0.2794)
						)
					)
					(width 0)
					(fill yes)
				)
			)
		)
	)
	(footprint ""
		(layer "F.Cu")
		(at 210.185 -439.674 180)
		(property "Reference" "PC1282"
			(at 0 0 180)
			(layer "F.SilkS")
			(hide yes)
			(effects
				(font
					(size 1.27 1.27)
				)
			)
		)
		(property "Value" "SC47U10V5MX-GP-U"
			(at -0.0762 -2.9972 180)
			(unlocked yes)
			(layer "F.Fab")
			(hide yes)
			(effects
				(font
					(size 1.016 1.016)
					(thickness 0.1524)
				)
			)
		)
		(property "Device Type" "C805H62"
			(at -0.0762 -4.5212 180)
			(unlocked yes)
			(layer "F.Fab")
			(hide yes)
			(effects
				(font
					(size 1.016 1.016)
					(thickness 0.1524)
				)
			)
		)
		(duplicate_pad_numbers_are_jumpers no)
		(fp_line
			(start 0.635 0)
			(end -0.635 0)
			(stroke
				(width 0.508)
				(type default)
			)
			(layer "F.SilkS")
		)
		(fp_rect
			(start -0.6223 1.0033)
			(end 0.6223 -1.0033)
			(stroke
				(width 0)
				(type default)
			)
			(fill no)
			(layer "F.CrtYd")
		)
		(fp_poly
			(pts
				(xy -0.9652 1.778) (xy -0.9652 -1.778) (xy 0.9652 -1.778) (xy 0.9652 0.39116) (xy 0.6223 0.39116)
				(xy 0.6223 -1.0033) (xy -0.6223 -1.0033) (xy -0.6223 1.0033) (xy 0.6223 1.0033) (xy 0.6223 0.3937)
				(xy 0.9652 0.3937) (xy 0.9652 1.778)
			)
			(stroke
				(width 0)
				(type default)
			)
			(fill no)
			(layer "F.CrtYd")
		)
		(fp_rect
			(start -0.9652 1.778)
			(end 0.9652 -1.778)
			(stroke
				(width 0)
				(type default)
			)
			(fill no)
			(layer "F.Fab")
		)
		(pad "1" smd rect
			(at 0 -0.9652 180)
			(size 1.397 1.143)
			(layers "F.Cu" "F.Mask" "F.Paste")
			(net "P3V3_OUT")
		)
		(pad "2" smd rect
			(at 0 0.9652 180)
			(size 1.397 1.143)
			(layers "F.Cu" "F.Mask" "F.Paste")
			(net "GND")
		)
	)
	(footprint ""
		(layer "F.Cu")
		(at 86.487 -110.236 180)
		(property "Reference" "R9060"
			(at 0 0 180)
			(layer "F.SilkS")
			(hide yes)
			(effects
				(font
					(size 1.27 1.27)
				)
			)
		)
		(property "Value" "27R2F-GP"
			(at 0.064008 -3.993896 180)
			(unlocked yes)
			(layer "F.Fab")
			(hide yes)
			(effects
				(font
					(size 1.016 1.016)
					(thickness 0.1524)
				)
			)
		)
		(property "Device Type" "R402H16"
			(at 0.064008 -5.517896 180)
			(unlocked yes)
			(layer "F.Fab")
			(hide yes)
			(effects
				(font
					(size 1.016 1.016)
					(thickness 0.1524)
				)
			)
		)
		(duplicate_pad_numbers_are_jumpers no)
		(fp_line
			(start 0.508 -0.9398)
			(end -0.508 -0.9398)
			(stroke
				(width 0.1524)
				(type default)
			)
			(layer "F.SilkS")
		)
		(fp_line
			(start -0.508 -0.9398)
			(end -0.508 0.9398)
			(stroke
				(width 0.1524)
				(type default)
			)
			(layer "F.SilkS")
		)
		(fp_rect
			(start -0.508 0.9398)
			(end 0.508 -0.9398)
			(stroke
				(width 0)
				(type default)
			)
			(fill no)
			(layer "F.CrtYd")
		)
		(fp_rect
			(start -0.508 0.9398)
			(end 0.508 -0.9398)
			(stroke
				(width 0)
				(type default)
			)
			(fill no)
			(layer "F.Fab")
		)
		(pad "1" smd custom
			(at 0 -0.4445 180)
			(size 0.1397 0.1397)
			(layers "F.Cu" "F.Mask" "F.Paste")
			(net "PE_CLK_100M_DR13_1_R_N")
			(options
				(clearance outline)
				(anchor circle)
			)
			(primitives
				(gr_poly
					(pts
						(arc
							(start -0.1778 -0.2794)
							(mid -0.249642 -0.249642)
							(end -0.2794 -0.1778)
						)
						(arc
							(start -0.2794 0.1778)
							(mid -0.249642 0.249642)
							(end -0.1778 0.2794)
						)
						(arc
							(start 0.1778 0.2794)
							(mid 0.249642 0.249642)
							(end 0.2794 0.1778)
						)
						(arc
							(start 0.2794 -0.1778)
							(mid 0.249642 -0.249642)
							(end 0.1778 -0.2794)
						)
					)
					(width 0)
					(fill yes)
				)
			)
		)
		(pad "2" smd custom
			(at 0 0.4445 180)
			(size 0.1397 0.1397)
			(layers "F.Cu" "F.Mask" "F.Paste")
			(net "PE_CLK100M_DR13_1_N")
			(options
				(clearance outline)
				(anchor circle)
			)
			(primitives
				(gr_poly
					(pts
						(arc
							(start -0.1778 -0.2794)
							(mid -0.249642 -0.249642)
							(end -0.2794 -0.1778)
						)
						(arc
							(start -0.2794 0.1778)
							(mid -0.249642 0.249642)
							(end -0.1778 0.2794)
						)
						(arc
							(start 0.1778 0.2794)
							(mid 0.249642 0.249642)
							(end 0.2794 0.1778)
						)
						(arc
							(start 0.2794 -0.1778)
							(mid 0.249642 -0.249642)
							(end 0.1778 -0.2794)
						)
					)
					(width 0)
					(fill yes)
				)
			)
		)
	)
	(footprint ""
		(layer "F.Cu")
		(at 86.614 -432.943 180)
		(property "Reference" "C8895"
			(at 0 0 180)
			(layer "F.SilkS")
			(hide yes)
			(effects
				(font
					(size 1.27 1.27)
				)
			)
		)
		(property "Value" "SC1U10V2KX-7-GP"
			(at 1.1811 -2.7051 180)
			(unlocked yes)
			(layer "F.Fab")
			(hide yes)
			(effects
				(font
					(size 1.016 1.016)
					(thickness 0.1524)
				)
			)
		)
		(property "Device Type" "C402H22"
			(at 1.1811 -4.2291 180)
			(unlocked yes)
			(layer "F.Fab")
			(hide yes)
			(effects
				(font
					(size 1.016 1.016)
					(thickness 0.1524)
				)
			)
		)
		(duplicate_pad_numbers_are_jumpers no)
		(fp_rect
			(start -0.4318 0.9525)
			(end 0.4318 -0.9525)
			(stroke
				(width 0)
				(type default)
			)
			(fill no)
			(layer "F.CrtYd")
		)
		(fp_rect
			(start -0.4318 0.9525)
			(end 0.4318 -0.9525)
			(stroke
				(width 0)
				(type default)
			)
			(fill no)
			(layer "F.Fab")
		)
		(pad "1" smd custom
			(at 0 -0.4445 180)
			(size 0.1524 0.1524)
			(layers "F.Cu" "F.Mask" "F.Paste")
			(net "VDDR_1")
			(options
				(clearance outline)
				(anchor circle)
			)
			(primitives
				(gr_poly
					(pts
						(arc
							(start 0.3048 -0.2032)
							(mid 0.275042 -0.275042)
							(end 0.2032 -0.3048)
						)
						(arc
							(start -0.2032 -0.3048)
							(mid -0.275042 -0.275042)
							(end -0.3048 -0.2032)
						)
						(arc
							(start -0.3048 0.2032)
							(mid -0.275042 0.275042)
							(end -0.2032 0.3048)
						)
						(arc
							(start 0.2032 0.3048)
							(mid 0.275042 0.275042)
							(end 0.3048 0.2032)
						)
					)
					(width 0)
					(fill yes)
				)
			)
		)
		(pad "2" smd custom
			(at 0 0.4445 180)
			(size 0.1524 0.1524)
			(layers "F.Cu" "F.Mask" "F.Paste")
			(net "GND")
			(options
				(clearance outline)
				(anchor circle)
			)
			(primitives
				(gr_poly
					(pts
						(arc
							(start 0.3048 -0.2032)
							(mid 0.275042 -0.275042)
							(end 0.2032 -0.3048)
						)
						(arc
							(start -0.2032 -0.3048)
							(mid -0.275042 -0.275042)
							(end -0.3048 -0.2032)
						)
						(arc
							(start -0.3048 0.2032)
							(mid -0.275042 0.275042)
							(end -0.2032 0.3048)
						)
						(arc
							(start 0.2032 0.3048)
							(mid 0.275042 0.275042)
							(end 0.3048 0.2032)
						)
					)
					(width 0)
					(fill yes)
				)
			)
		)
	)
	(footprint ""
		(layer "F.Cu")
		(at 91.186 -30.607 -90)
		(property "Reference" "C352"
			(at 0 0 270)
			(layer "F.SilkS")
			(hide yes)
			(effects
				(font
					(size 1.27 1.27)
				)
			)
		)
		(property "Value" "SCD1U16V2KX-3GP"
			(at 1.1811 -2.7051 270)
			(unlocked yes)
			(layer "F.Fab")
			(hide yes)
			(effects
				(font
					(size 1.016 1.016)
					(thickness 0.1524)
				)
			)
		)
		(property "Device Type" "C402H22"
			(at 1.1811 -4.2291 270)
			(unlocked yes)
			(layer "F.Fab")
			(hide yes)
			(effects
				(font
					(size 1.016 1.016)
					(thickness 0.1524)
				)
			)
		)
		(duplicate_pad_numbers_are_jumpers no)
		(fp_rect
			(start -0.4318 0.9525)
			(end 0.4318 -0.9525)
			(stroke
				(width 0)
				(type default)
			)
			(fill no)
			(layer "F.CrtYd")
		)
		(fp_rect
			(start -0.4318 0.9525)
			(end 0.4318 -0.9525)
			(stroke
				(width 0)
				(type default)
			)
			(fill no)
			(layer "F.Fab")
		)
		(pad "1" smd custom
			(at 0 -0.4445 270)
			(size 0.1524 0.1524)
			(layers "F.Cu" "F.Mask" "F.Paste")
			(net "P3V3")
			(options
				(clearance outline)
				(anchor circle)
			)
			(primitives
				(gr_poly
					(pts
						(arc
							(start 0.3048 -0.2032)
							(mid 0.275042 -0.275042)
							(end 0.2032 -0.3048)
						)
						(arc
							(start -0.2032 -0.3048)
							(mid -0.275042 -0.275042)
							(end -0.3048 -0.2032)
						)
						(arc
							(start -0.3048 0.2032)
							(mid -0.275042 0.275042)
							(end -0.2032 0.3048)
						)
						(arc
							(start 0.2032 0.3048)
							(mid 0.275042 0.275042)
							(end 0.3048 0.2032)
						)
					)
					(width 0)
					(fill yes)
				)
			)
		)
		(pad "2" smd custom
			(at 0 0.4445 270)
			(size 0.1524 0.1524)
			(layers "F.Cu" "F.Mask" "F.Paste")
			(net "GND")
			(options
				(clearance outline)
				(anchor circle)
			)
			(primitives
				(gr_poly
					(pts
						(arc
							(start 0.3048 -0.2032)
							(mid 0.275042 -0.275042)
							(end 0.2032 -0.3048)
						)
						(arc
							(start -0.2032 -0.3048)
							(mid -0.275042 -0.275042)
							(end -0.3048 -0.2032)
						)
						(arc
							(start -0.3048 0.2032)
							(mid -0.275042 0.275042)
							(end -0.2032 0.3048)
						)
						(arc
							(start 0.2032 0.3048)
							(mid 0.275042 0.275042)
							(end 0.3048 0.2032)
						)
					)
					(width 0)
					(fill yes)
				)
			)
		)
	)
)
